FILE_TYPE = CONNECTIVITY;
{Allegro Design Entry HDL 17.2-2016 S081 (4005846) 1/11/2022}
"PAGE_NUMBER" = 18;
0"NC";
END.
